(kicad_pcb
	(version 20241229)
	(generator "pcbnew")
	(generator_version "9.0")
	(general
		(thickness 1.711)
		(legacy_teardrops no)
	)
	(paper "A4")
	(title_block
		(title "Antmicro Baseboard for Jetson AGX Thor")
		(date "2026-02-18")
		(rev "1.1.0")
		(company "Antmicro Ltd")
		(comment 1 "www.antmicro.com")
		(comment 9 "footprint 110 of 1170 (J1), pads 81-161 of 699")
	)
	(layers
		(0 "F.Cu" signal)
		(4 "In1.Cu" signal)
		(6 "In2.Cu" signal)
		(8 "In3.Cu" signal)
		(10 "In4.Cu" jumper)
		(12 "In5.Cu" signal)
		(14 "In6.Cu" signal)
		(16 "In7.Cu" signal)
		(18 "In8.Cu" signal)
		(2 "B.Cu" signal)
		(9 "F.Adhes" user "F.Adhesive")
		(11 "B.Adhes" user "B.Adhesive")
		(13 "F.Paste" user)
		(15 "B.Paste" user)
		(5 "F.SilkS" user "F.Silkscreen")
		(7 "B.SilkS" user "B.Silkscreen")
		(1 "F.Mask" user)
		(3 "B.Mask" user)
		(17 "Dwgs.User" user "User.Drawings")
		(19 "Cmts.User" user "User.Comments")
		(21 "Eco1.User" user "User.Eco1")
		(23 "Eco2.User" user "User.Eco2")
		(25 "Edge.Cuts" user)
		(27 "Margin" user)
		(31 "F.CrtYd" user "F.Courtyard")
		(29 "B.CrtYd" user "B.Courtyard")
		(35 "F.Fab" user)
		(33 "B.Fab" user)
	)
	(footprint "antmicro-footprints:Conn_Hermaphroditic_Molex_203456-0003_mirrored"
		(locked yes)
		(layer "F.Cu")
		(at 116.530532 78.15)
		(descr "Mirrored version of: https://www.molex.com/content/dam/molex/molex-dot-com/products/automated/en-us/salesdrawingpdf/203/203456/2034560003_sd.pdf")
		(property "Reference" "J1"
			(at -32.25 -11.2 180)
			(layer "F.SilkS")
			(effects
				(font
					(size 0.7 0.7)
					(thickness 0.15)
				)
				(justify right top)
			)
		)
		(property "Value" "Hermaphroditic_Molex_203456-0003_CUSTOM_Jetson_AGX_Thor_H8mm"
			(at 0.1 12.9 0)
			(layer "F.Fab")
			(effects
				(font
					(size 0.7 0.7)
					(thickness 0.15)
				)
				(justify right top)
			)
		)
		(property "Datasheet" "https://www.molex.com/content/dam/molex/molex-dot-com/products/automated/en-us/salesdrawingpdf/203/203456/2034560003_sd.pdf?inline"
			(at 0.1 0.2 0)
			(layer "F.Fab")
			(hide yes)
			(effects
				(font
					(size 0.7 0.7)
					(thickness 0.15)
				)
				(justify right top)
			)
		)
		(property "Description" "Mirror Mezz Hermaphroditic Connector, 5.50mm Connector Height, BGA-Attach Mounting, 7 Pair, 11 Row, 699 Circuits, 0.76µm Gold Plating, without Pegs"
			(at 0.1 0.2 0)
			(layer "F.Fab")
			(hide yes)
			(effects
				(font
					(size 0.7 0.7)
					(thickness 0.15)
				)
				(justify right top)
			)
		)
		(property "MPN" "203456-0003"
			(at 0 0 0)
			(unlocked yes)
			(layer "F.Fab")
			(hide yes)
			(effects
				(font
					(size 1 1)
					(thickness 0.15)
				)
			)
		)
		(property "Manufacturer" "Molex"
			(at 0 0 0)
			(unlocked yes)
			(layer "F.Fab")
			(hide yes)
			(effects
				(font
					(size 1 1)
					(thickness 0.15)
				)
			)
		)
		(property "Author" "Antmicro"
			(at 0 0 0)
			(unlocked yes)
			(layer "F.Fab")
			(hide yes)
			(effects
				(font
					(size 1 1)
					(thickness 0.15)
				)
			)
		)
		(property "License" "Apache-2.0"
			(at 0 0 0)
			(unlocked yes)
			(layer "F.Fab")
			(hide yes)
			(effects
				(font
					(size 1 1)
					(thickness 0.15)
				)
			)
		)
		(sheetname "/SoM_IO/")
		(sheetfile "som_io.kicad_sch")
		(solder_mask_margin 0.05)
		(attr smd)
		(pad "B22" smd circle
			(at -10.3 6 90)
			(size 0.5 0.5)
			(layers "F.Cu" "F.Mask" "F.Paste")
			(net 1 "GND")
			(pinfunction "GND")
			(pintype "passive")
		)
		(pad "B23" smd circle
			(at -9 6 90)
			(size 0.5 0.5)
			(layers "F.Cu" "F.Mask" "F.Paste")
			(net 1 "GND")
			(pinfunction "GND")
			(pintype "passive")
		)
		(pad "B24" smd circle
			(at -8.1 6 90)
			(size 0.5 0.5)
			(layers "F.Cu" "F.Mask" "F.Paste")
			(net 620 "/M.2/PCIe_{C5x4}.RX1-")
			(pinfunction "UPHY_RX9_N")
			(pintype "input")
		)
		(pad "B25" smd circle
			(at -7.2 6 90)
			(size 0.5 0.5)
			(layers "F.Cu" "F.Mask" "F.Paste")
			(net 674 "/M.2/PCIe_{C5x4}.RX1+")
			(pinfunction "UPHY_RX9_P")
			(pintype "input")
		)
		(pad "B26" smd circle
			(at -6.3 6 90)
			(size 0.5 0.5)
			(layers "F.Cu" "F.Mask" "F.Paste")
			(net 1 "GND")
			(pinfunction "GND")
			(pintype "passive")
		)
		(pad "B27" smd circle
			(at -5 6 90)
			(size 0.5 0.5)
			(layers "F.Cu" "F.Mask" "F.Paste")
			(net 1 "GND")
			(pinfunction "GND")
			(pintype "passive")
		)
		(pad "B28" smd circle
			(at -4.1 6 90)
			(size 0.5 0.5)
			(layers "F.Cu" "F.Mask" "F.Paste")
			(net 667 "unconnected-(J1B-UPHY_RX13_N-PadB28)")
			(pinfunction "UPHY_RX13_N")
			(pintype "input+no_connect")
		)
		(pad "B29" smd circle
			(at -3.2 6 90)
			(size 0.5 0.5)
			(layers "F.Cu" "F.Mask" "F.Paste")
			(net 559 "unconnected-(J1B-UPHY_RX13_P-PadB29)")
			(pinfunction "UPHY_RX13_P")
			(pintype "input+no_connect")
		)
		(pad "B30" smd circle
			(at -2.3 6 90)
			(size 0.5 0.5)
			(layers "F.Cu" "F.Mask" "F.Paste")
			(net 1 "GND")
			(pinfunction "GND")
			(pintype "passive")
		)
		(pad "B31" smd circle
			(at -1 6 90)
			(size 0.5 0.5)
			(layers "F.Cu" "F.Mask" "F.Paste")
			(net 1 "GND")
			(pinfunction "GND")
			(pintype "power_in")
		)
		(pad "B32" smd circle
			(at -0.1 6 90)
			(size 0.5 0.5)
			(layers "F.Cu" "F.Mask" "F.Paste")
			(net 94 "/M.2/PCIe_{C1x1}.RX0-")
			(pinfunction "UPHY_RX3_N")
			(pintype "input")
		)
		(pad "B33" smd circle
			(at 0.8 6 90)
			(size 0.5 0.5)
			(layers "F.Cu" "F.Mask" "F.Paste")
			(net 130 "/M.2/PCIe_{C1x1}.RX0+")
			(pinfunction "UPHY_RX3_P")
			(pintype "input")
		)
		(pad "B34" smd circle
			(at 1.7 6 90)
			(size 0.5 0.5)
			(layers "F.Cu" "F.Mask" "F.Paste")
			(net 1 "GND")
			(pinfunction "GND")
			(pintype "passive")
		)
		(pad "B35" smd circle
			(at 3 6 90)
			(size 0.5 0.5)
			(layers "F.Cu" "F.Mask" "F.Paste")
			(net 1 "GND")
			(pinfunction "GND")
			(pintype "passive")
		)
		(pad "B36" smd circle
			(at 3.9 6 90)
			(size 0.5 0.5)
			(layers "F.Cu" "F.Mask" "F.Paste")
			(net 679 "/M.2/PCIe_{C1x1}.~{RST}")
			(pinfunction "PEX_C1_RST_N")
			(pintype "output")
		)
		(pad "B37" smd circle
			(at 4.8 6 90)
			(size 0.5 0.5)
			(layers "F.Cu" "F.Mask" "F.Paste")
			(net 137 "/M.2/PCIe_{C1x1}.~{CLKREQ}")
			(pinfunction "PEX_C1_CLKREQ_N")
			(pintype "bidirectional")
		)
		(pad "B38" smd circle
			(at 5.7 6 90)
			(size 0.5 0.5)
			(layers "F.Cu" "F.Mask" "F.Paste")
			(net 1 "GND")
			(pinfunction "GND")
			(pintype "passive")
		)
		(pad "B39" smd circle
			(at 7 6 90)
			(size 0.5 0.5)
			(layers "F.Cu" "F.Mask" "F.Paste")
			(net 1 "GND")
			(pinfunction "GND")
			(pintype "passive")
		)
		(pad "B40" smd circle
			(at 7.9 6 90)
			(size 0.5 0.5)
			(layers "F.Cu" "F.Mask" "F.Paste")
			(net 613 "unconnected-(J1G-FSI_GPIO02-PadB40)")
			(pinfunction "FSI_GPIO02")
			(pintype "passive+no_connect")
		)
		(pad "B41" smd circle
			(at 8.8 6 90)
			(size 0.5 0.5)
			(layers "F.Cu" "F.Mask" "F.Paste")
			(net 1 "GND")
			(pinfunction "GND")
			(pintype "passive")
		)
		(pad "B42" smd circle
			(at 9.7 6 90)
			(size 0.5 0.5)
			(layers "F.Cu" "F.Mask" "F.Paste")
			(net 68 "/CSI/CAM0.CSI2_CLK-")
			(pinfunction "CSI2_CLK_N")
			(pintype "input")
		)
		(pad "B43" smd circle
			(at 10.6 6 90)
			(size 0.5 0.5)
			(layers "F.Cu" "F.Mask" "F.Paste")
			(net 249 "/CSI/CAM0.CSI2_CLK+")
			(pinfunction "CSI2_CLK_P")
			(pintype "input")
		)
		(pad "B44" smd circle
			(at 11.5 6 90)
			(size 0.5 0.5)
			(layers "F.Cu" "F.Mask" "F.Paste")
			(net 1 "GND")
			(pinfunction "GND")
			(pintype "passive")
		)
		(pad "B45" smd circle
			(at 12.4 6 90)
			(size 0.5 0.5)
			(layers "F.Cu" "F.Mask" "F.Paste")
			(net 92 "unconnected-(J1F-CSI7_CLK_P-PadB45)")
			(pinfunction "CSI7_CLK_P")
			(pintype "input+no_connect")
		)
		(pad "B46" smd circle
			(at 13.3 6 90)
			(size 0.5 0.5)
			(layers "F.Cu" "F.Mask" "F.Paste")
			(net 73 "unconnected-(J1F-CSI7_CLK_N-PadB46)")
			(pinfunction "CSI7_CLK_N")
			(pintype "input+no_connect")
		)
		(pad "B47" smd circle
			(at 14.2 6 90)
			(size 0.5 0.5)
			(layers "F.Cu" "F.Mask" "F.Paste")
			(net 1 "GND")
			(pinfunction "GND")
			(pintype "passive")
		)
		(pad "B48" smd circle
			(at 15.1 6 90)
			(size 0.5 0.5)
			(layers "F.Cu" "F.Mask" "F.Paste")
			(net 647 "unconnected-(J1G-FSI_GPIO16-PadB48)")
			(pinfunction "FSI_GPIO16")
			(pintype "passive+no_connect")
		)
		(pad "B49" smd circle
			(at 16 6 90)
			(size 0.5 0.5)
			(layers "F.Cu" "F.Mask" "F.Paste")
			(net 718 "unconnected-(J1G-FSI_GPIO17-PadB49)")
			(pinfunction "FSI_GPIO17")
			(pintype "passive+no_connect")
		)
		(pad "B50" smd circle
			(at 16.9 6 90)
			(size 0.5 0.5)
			(layers "F.Cu" "F.Mask" "F.Paste")
			(net 1 "GND")
			(pinfunction "GND")
			(pintype "passive")
		)
		(pad "B51" smd circle
			(at 17.8 6 90)
			(size 0.5 0.5)
			(layers "F.Cu" "F.Mask" "F.Paste")
			(net 596 "/SoM_IO2/DP0.TX1_C+")
			(pinfunction "DP0_D1_HDMI_D1_P")
			(pintype "output")
		)
		(pad "B52" smd circle
			(at 18.7 6 90)
			(size 0.5 0.5)
			(layers "F.Cu" "F.Mask" "F.Paste")
			(net 597 "/SoM_IO2/DP0.TX1_C-")
			(pinfunction "DP0_D1_HDMI_D1_N")
			(pintype "output")
		)
		(pad "B53" smd circle
			(at 19.6 6 90)
			(size 0.5 0.5)
			(layers "F.Cu" "F.Mask" "F.Paste")
			(net 1 "GND")
			(pinfunction "GND")
			(pintype "passive")
		)
		(pad "B54" smd circle
			(at 20.5 6 90)
			(size 0.5 0.5)
			(layers "F.Cu" "F.Mask" "F.Paste")
			(net 155 "/CSI/CAM_CTRL.VSYNC_CAM0")
			(pinfunction "GPIO45")
			(pintype "passive")
		)
		(pad "B55" smd circle
			(at 21.4 6 90)
			(size 0.5 0.5)
			(layers "F.Cu" "F.Mask" "F.Paste")
			(net 704 "Net-(J1A-GPIO30)")
			(pinfunction "GPIO30")
			(pintype "passive")
		)
		(pad "B56" smd circle
			(at 22.3 6 90)
			(size 0.5 0.5)
			(layers "F.Cu" "F.Mask" "F.Paste")
			(net 364 "/Expansion connector/SPI1.~{CS1}")
			(pinfunction "SPI1_CS1_N")
			(pintype "bidirectional")
		)
		(pad "B57" smd circle
			(at 23.2 6 90)
			(size 0.5 0.5)
			(layers "F.Cu" "F.Mask" "F.Paste")
			(net 1 "GND")
			(pinfunction "GND")
			(pintype "passive")
		)
		(pad "B58" smd circle
			(at 24.1 6 90)
			(size 0.5 0.5)
			(layers "F.Cu" "F.Mask" "F.Paste")
			(net 341 "/Expansion connector/FMC_PRESENT")
			(pinfunction "GPIO21")
			(pintype "passive")
		)
		(pad "B59" smd circle
			(at 25 6 90)
			(size 0.5 0.5)
			(layers "F.Cu" "F.Mask" "F.Paste")
			(net 342 "/Expansion connector/FMC_PG_C2M")
			(pinfunction "GPIO04")
			(pintype "passive")
		)
		(pad "B60" smd circle
			(at 25.9 6 90)
			(size 0.5 0.5)
			(layers "F.Cu" "F.Mask" "F.Paste")
			(net 715 "/SoM_IO2/JTAG_TDI")
			(pinfunction "JTAG_TDI")
			(pintype "passive")
		)
		(pad "B61" smd circle
			(at 26.8 6 90)
			(size 0.5 0.5)
			(layers "F.Cu" "F.Mask" "F.Paste")
			(net 701 "/Expansion connector/CAN3.DIN")
			(pinfunction "CAN3_DIN")
			(pintype "input")
		)
		(pad "B62" smd circle
			(at 27.7 6 90)
			(size 0.5 0.5)
			(layers "F.Cu" "F.Mask" "F.Paste")
			(net 371 "/Expansion connector/GPIO.USER_LED1")
			(pinfunction "GPIO08")
			(pintype "passive")
		)
		(pad "B63" smd circle
			(at 28.6 6 90)
			(size 0.5 0.5)
			(layers "F.Cu" "F.Mask" "F.Paste")
			(net 12 "SYS_VIN_HV")
			(pinfunction "SYS_VIN_HV")
			(pintype "passive")
		)
		(pad "C1" smd circle
			(at -30.2 4.5 90)
			(size 0.5 0.5)
			(layers "F.Cu" "F.Mask" "F.Paste")
			(net 12 "SYS_VIN_HV")
			(pinfunction "SYS_VIN_HV")
			(pintype "passive")
		)
		(pad "C2" smd circle
			(at -29.3 4.5 90)
			(size 0.5 0.5)
			(layers "F.Cu" "F.Mask" "F.Paste")
			(net 12 "SYS_VIN_HV")
			(pinfunction "SYS_VIN_HV")
			(pintype "passive")
		)
		(pad "C3" smd circle
			(at -28.4 4.5 90)
			(size 0.5 0.5)
			(layers "F.Cu" "F.Mask" "F.Paste")
			(net 1 "GND")
			(pinfunction "GND")
			(pintype "passive")
		)
		(pad "C4" smd circle
			(at -27.5 4.5 90)
			(size 0.5 0.5)
			(layers "F.Cu" "F.Mask" "F.Paste")
			(net 67 "/CSI/CAM_CTRL.VSYNC_CAM2")
			(pinfunction "GPIO47")
			(pintype "passive")
		)
		(pad "C5" smd circle
			(at -26.6 4.5 90)
			(size 0.5 0.5)
			(layers "F.Cu" "F.Mask" "F.Paste")
			(net 560 "unconnected-(J1H-GPIO40-PadC5)")
			(pinfunction "GPIO40")
			(pintype "output+no_connect")
		)
		(pad "C6" smd circle
			(at -25.7 4.5 90)
			(size 0.5 0.5)
			(layers "F.Cu" "F.Mask" "F.Paste")
			(net 796 "Net-(J1A-UFS0_RST_N)")
			(pinfunction "UFS0_RST_N")
			(pintype "passive")
		)
		(pad "C7" smd circle
			(at -24.8 4.5 90)
			(size 0.5 0.5)
			(layers "F.Cu" "F.Mask" "F.Paste")
			(net 72 "/SoM_IO/I2S_{M.2}.SDOUT")
			(pinfunction "I2S1_SDOUT")
			(pintype "output")
		)
		(pad "C8" smd circle
			(at -23.9 4.5 90)
			(size 0.5 0.5)
			(layers "F.Cu" "F.Mask" "F.Paste")
			(net 588 "unconnected-(J1C-PEX_C4_CLKREQ_N-PadC8)")
			(pinfunction "PEX_C4_CLKREQ_N")
			(pintype "bidirectional+no_connect")
		)
		(pad "C9" smd circle
			(at -23 4.5 90)
			(size 0.5 0.5)
			(layers "F.Cu" "F.Mask" "F.Paste")
			(net 1 "GND")
			(pinfunction "GND")
			(pintype "passive")
		)
		(pad "C10" smd circle
			(at -22.1 4.5 90)
			(size 0.5 0.5)
			(layers "F.Cu" "F.Mask" "F.Paste")
			(net 140 "/SoM_IO2/USB1.D-")
			(pinfunction "USB1_N")
			(pintype "bidirectional")
		)
		(pad "C11" smd circle
			(at -21.2 4.5 90)
			(size 0.5 0.5)
			(layers "F.Cu" "F.Mask" "F.Paste")
			(net 55 "/SoM_IO2/USB1.D+")
			(pinfunction "USB1_P")
			(pintype "bidirectional")
		)
		(pad "C12" smd circle
			(at -20.3 4.5 90)
			(size 0.5 0.5)
			(layers "F.Cu" "F.Mask" "F.Paste")
			(net 1 "GND")
			(pinfunction "GND")
			(pintype "passive")
		)
		(pad "C13" smd circle
			(at -19 4.5 90)
			(size 0.5 0.5)
			(layers "F.Cu" "F.Mask" "F.Paste")
			(net 1 "GND")
			(pinfunction "GND")
			(pintype "passive")
		)
		(pad "C14" smd circle
			(at -18.1 4.5 90)
			(size 0.5 0.5)
			(layers "F.Cu" "F.Mask" "F.Paste")
			(net 1260 "/SoM_IO2/DP2.TX2_C-")
			(pinfunction "DP2_D2_HDMI_D0_N")
			(pintype "output")
		)
		(pad "C15" smd circle
			(at -17.2 4.5 90)
			(size 0.5 0.5)
			(layers "F.Cu" "F.Mask" "F.Paste")
			(net 1256 "/SoM_IO2/DP2.TX2_C+")
			(pinfunction "DP2_D2_HDMI_D0_P")
			(pintype "output")
		)
		(pad "C16" smd circle
			(at -16.3 4.5 90)
			(size 0.5 0.5)
			(layers "F.Cu" "F.Mask" "F.Paste")
			(net 1 "GND")
			(pinfunction "GND")
			(pintype "passive")
		)
		(pad "C17" smd circle
			(at -15 4.5 90)
			(size 0.5 0.5)
			(layers "F.Cu" "F.Mask" "F.Paste")
			(net 1 "GND")
			(pinfunction "GND")
			(pintype "passive")
		)
		(pad "C18" smd circle
			(at -14.1 4.5 90)
			(size 0.5 0.5)
			(layers "F.Cu" "F.Mask" "F.Paste")
			(net 781 "/Expansion connector/DP1.HPD")
			(pinfunction "HPD1")
			(pintype "bidirectional")
		)
		(pad "C19" smd circle
			(at -13.2 4.5 90)
			(size 0.5 0.5)
			(layers "F.Cu" "F.Mask" "F.Paste")
			(net 574 "/Expansion connector/DP3.HPD")
			(pinfunction "HPD3")
			(pintype "bidirectional")
		)
		(pad "C20" smd circle
			(at -12.3 4.5 90)
			(size 0.5 0.5)
			(layers "F.Cu" "F.Mask" "F.Paste")
			(net 1 "GND")
			(pinfunction "GND")
			(pintype "passive")
		)
		(pad "C21" smd circle
			(at -11 4.5 90)
			(size 0.5 0.5)
			(layers "F.Cu" "F.Mask" "F.Paste")
			(net 1 "GND")
			(pinfunction "GND")
			(pintype "passive")
		)
		(pad "C22" smd circle
			(at -10.1 4.5 90)
			(size 0.5 0.5)
			(layers "F.Cu" "F.Mask" "F.Paste")
			(net 623 "/SoM_IO2/USBSS2.RX-")
			(pinfunction "UPHY_RX2_N")
			(pintype "input")
		)
		(pad "C23" smd circle
			(at -9.2 4.5 90)
			(size 0.5 0.5)
			(layers "F.Cu" "F.Mask" "F.Paste")
			(net 770 "/SoM_IO2/USBSS2.RX+")
			(pinfunction "UPHY_RX2_P")
			(pintype "input")
		)
		(pad "C24" smd circle
			(at -8.3 4.5 90)
			(size 0.5 0.5)
			(layers "F.Cu" "F.Mask" "F.Paste")
			(net 1 "GND")
			(pinfunction "GND")
			(pintype "passive")
		)
		(pad "C25" smd circle
			(at -7 4.5 90)
			(size 0.5 0.5)
			(layers "F.Cu" "F.Mask" "F.Paste")
			(net 1 "GND")
			(pinfunction "GND")
			(pintype "passive")
		)
		(pad "C26" smd circle
			(at -6.1 4.5 90)
			(size 0.5 0.5)
			(layers "F.Cu" "F.Mask" "F.Paste")
			(net 552 "/M.2/PCIe_{C5x4}.RX2-")
			(pinfunction "UPHY_RX10_N")
			(pintype "input")
		)
		(pad "C27" smd circle
			(at -5.2 4.5 90)
			(size 0.5 0.5)
			(layers "F.Cu" "F.Mask" "F.Paste")
			(net 731 "/M.2/PCIe_{C5x4}.RX2+")
			(pinfunction "UPHY_RX10_P")
			(pintype "input")
		)
		(pad "C28" smd circle
			(at -4.3 4.5 90)
			(size 0.5 0.5)
			(layers "F.Cu" "F.Mask" "F.Paste")
			(net 1 "GND")
			(pinfunction "GND")
			(pintype "passive")
		)
		(pad "C29" smd circle
			(at -3 4.5 90)
			(size 0.5 0.5)
			(layers "F.Cu" "F.Mask" "F.Paste")
			(net 1 "GND")
			(pinfunction "GND")
			(pintype "passive")
		)
		(pad "C30" smd circle
			(at -2.1 4.5 90)
			(size 0.5 0.5)
			(layers "F.Cu" "F.Mask" "F.Paste")
			(net 697 "unconnected-(J1B-UPHY_RX14_N-PadC30)")
			(pinfunction "UPHY_RX14_N")
			(pintype "input+no_connect")
		)
		(pad "C31" smd circle
			(at -1.2 4.5 90)
			(size 0.5 0.5)
			(layers "F.Cu" "F.Mask" "F.Paste")
			(net 573 "unconnected-(J1B-UPHY_RX14_P-PadC31)")
			(pinfunction "UPHY_RX14_P")
			(pintype "input+no_connect")
		)
		(pad "C32" smd circle
			(at -0.3 4.5 90)
			(size 0.5 0.5)
			(layers "F.Cu" "F.Mask" "F.Paste")
			(net 1 "GND")
			(pinfunction "GND")
			(pintype "passive")
		)
		(pad "C33" smd circle
			(at 1 4.5 90)
			(size 0.5 0.5)
			(layers "F.Cu" "F.Mask" "F.Paste")
			(net 1 "GND")
			(pinfunction "GND")
			(pintype "passive")
		)
		(pad "C34" smd circle
			(at 1.9 4.5 90)
			(size 0.5 0.5)
			(layers "F.Cu" "F.Mask" "F.Paste")
			(net 598 "/Recovery USB/USBSS0.RX+")
			(pinfunction "UPHY_RX0_P")
			(pintype "input")
		)
		(pad "C35" smd circle
			(at 2.8 4.5 90)
			(size 0.5 0.5)
			(layers "F.Cu" "F.Mask" "F.Paste")
			(net 622 "/Recovery USB/USBSS0.RX-")
			(pinfunction "UPHY_RX0_N")
			(pintype "input")
		)
		(pad "C36" smd circle
			(at 3.7 4.5 90)
			(size 0.5 0.5)
			(layers "F.Cu" "F.Mask" "F.Paste")
			(net 1 "GND")
			(pinfunction "GND")
			(pintype "passive")
		)
		(pad "C37" smd circle
			(at 5 4.5 90)
			(size 0.5 0.5)
			(layers "F.Cu" "F.Mask" "F.Paste")
			(net 1 "GND")
			(pinfunction "GND")
			(pintype "passive")
		)
		(pad "C38" smd circle
			(at 5.9 4.5 90)
			(size 0.5 0.5)
			(layers "F.Cu" "F.Mask" "F.Paste")
			(net 692 "/SoM_IO/~{USBC2_INT}_1V8")
			(pinfunction "GPIO32")
			(pintype "passive")
		)
		(pad "C39" smd circle
			(at 6.8 4.5 90)
			(size 0.5 0.5)
			(layers "F.Cu" "F.Mask" "F.Paste")
			(net 906 "/SoM_IO/M2_E_W_DIS_1_1V8")
			(pinfunction "GPIO18")
			(pintype "passive")
		)
	)
)
